(kicad_pcb
	(version 20260206)
	(generator "pcbnew")
	(generator_version "10.0")
	(general
		(thickness 1.6)
		(legacy_teardrops no)
	)
	(paper "A4")
	(title_block
		(title "03242023_DA0F0TMBIJ0_F0T_Motherboard_J_brd_V01_OCP.brd")
		(comment 1 "Grand Teton / footprints 2195-2200 of 6105")
	)
	(layers
		(0 "F.Cu" signal "TOP")
		(4 "In1.Cu" signal "GND")
		(6 "In2.Cu" signal "IN1")
		(8 "In3.Cu" signal "GND1")
		(10 "In4.Cu" signal "IN2")
		(12 "In5.Cu" signal "GND2")
		(14 "In6.Cu" signal "IN3")
		(16 "In7.Cu" signal "GND3")
		(18 "In8.Cu" signal "VCC")
		(20 "In9.Cu" signal "VCC1")
		(22 "In10.Cu" signal "GND4")
		(24 "In11.Cu" signal "IN4")
		(26 "In12.Cu" signal "GND5")
		(28 "In13.Cu" signal "IN5")
		(30 "In14.Cu" signal "GND6")
		(32 "In15.Cu" signal "IN6")
		(34 "In16.Cu" signal "GND7")
		(2 "B.Cu" signal "BOTTOM")
		(9 "F.Adhes" user "F.Adhesive")
		(11 "B.Adhes" user "B.Adhesive")
		(13 "F.Paste" user "Package Geometry/Pastemask Top")
		(15 "B.Paste" user "Package Geometry/Pastemask Bottom")
		(5 "F.SilkS" user "Ref Des/Silkscreen Top")
		(7 "B.SilkS" user "Ref Des/Silkscreen Bottom")
		(1 "F.Mask" user "Board Geometry/Soldermask Top")
		(3 "B.Mask" user "Board Geometry/Soldermask Bottom")
		(17 "Dwgs.User" user "User.Drawings")
		(19 "Cmts.User" user "User.Comments")
		(21 "Eco1.User" user "User.Eco1")
		(23 "Eco2.User" user "User.Eco2")
		(25 "Edge.Cuts" user "Board Geometry/Outline")
		(27 "Margin" user)
		(31 "F.CrtYd" user "Package Geometry/Place Bound Top")
		(29 "B.CrtYd" user "Package Geometry/Place Bound Bottom")
		(35 "F.Fab" user "Ref Des/Assembly Top")
		(33 "B.Fab" user "Ref Des/Assembly Bottom")
	)
	(footprint ""
		(layer "F.Cu")
		(at 61.90488 -18.252948)
		(property "Reference" "R3217"
			(at 0 0 0)
			(layer "F.SilkS")
			(hide yes)
			(effects
				(font
					(size 1.27 1.27)
				)
			)
		)
		(property "Value" ""
			(at 0 0 0)
			(layer "F.Fab")
			(effects
				(font
					(size 1.27 1.27)
				)
			)
		)
		(duplicate_pad_numbers_are_jumpers no)
		(fp_line
			(start -0.7874 -0.4064)
			(end 0.7874 -0.4064)
			(stroke
				(width 0.1524)
				(type default)
			)
			(layer "F.SilkS")
		)
		(fp_line
			(start -0.7874 0.4064)
			(end -0.7874 -0.4064)
			(stroke
				(width 0.1524)
				(type default)
			)
			(layer "F.SilkS")
		)
		(fp_line
			(start 0.7874 -0.4064)
			(end 0.7874 0.4064)
			(stroke
				(width 0.1524)
				(type default)
			)
			(layer "F.SilkS")
		)
		(fp_line
			(start 0.7874 0.4064)
			(end -0.7874 0.4064)
			(stroke
				(width 0.1524)
				(type default)
			)
			(layer "F.SilkS")
		)
		(fp_line
			(start -0.67945 -0.305054)
			(end -0.12065 -0.305054)
			(stroke
				(width 0.1)
				(type default)
			)
			(layer "F.Fab")
		)
		(fp_line
			(start -0.67945 0.3048)
			(end -0.67945 -0.305054)
			(stroke
				(width 0.1)
				(type default)
			)
			(layer "F.Fab")
		)
		(fp_line
			(start -0.12065 -0.305054)
			(end -0.12065 -0.2794)
			(stroke
				(width 0.1)
				(type default)
			)
			(layer "F.Fab")
		)
		(fp_line
			(start -0.12065 -0.2794)
			(end 0.12065 -0.2794)
			(stroke
				(width 0.1)
				(type default)
			)
			(layer "F.Fab")
		)
		(fp_line
			(start -0.12065 0.2794)
			(end -0.12065 0.3048)
			(stroke
				(width 0.1)
				(type default)
			)
			(layer "F.Fab")
		)
		(fp_line
			(start -0.12065 0.3048)
			(end -0.67945 0.3048)
			(stroke
				(width 0.1)
				(type default)
			)
			(layer "F.Fab")
		)
		(fp_line
			(start 0.120396 0.2794)
			(end -0.12065 0.2794)
			(stroke
				(width 0.1)
				(type default)
			)
			(layer "F.Fab")
		)
		(fp_line
			(start 0.120396 0.3048)
			(end 0.120396 0.2794)
			(stroke
				(width 0.1)
				(type default)
			)
			(layer "F.Fab")
		)
		(fp_line
			(start 0.12065 -0.3048)
			(end 0.67945 -0.3048)
			(stroke
				(width 0.1)
				(type default)
			)
			(layer "F.Fab")
		)
		(fp_line
			(start 0.12065 -0.2794)
			(end 0.12065 -0.3048)
			(stroke
				(width 0.1)
				(type default)
			)
			(layer "F.Fab")
		)
		(fp_line
			(start 0.67945 -0.3048)
			(end 0.67945 0.3048)
			(stroke
				(width 0.1)
				(type default)
			)
			(layer "F.Fab")
		)
		(fp_line
			(start 0.67945 0.3048)
			(end 0.120396 0.3048)
			(stroke
				(width 0.1)
				(type default)
			)
			(layer "F.Fab")
		)
		(pad "1" smd circle
			(at -0.40005 0)
			(size 0 0)
			(layers "F.Cu" "F.Mask" "F.Paste")
			(net "OCP_V3_2_ISO_BIF2_EN")
		)
		(pad "2" smd circle
			(at 0.40005 0)
			(size 0 0)
			(layers "F.Cu" "F.Mask" "F.Paste")
			(net "GND")
		)
	)
	(footprint ""
		(layer "F.Cu")
		(at 68.085716 -108.39069)
		(property "Reference" "R3721"
			(at 0 0 0)
			(layer "F.SilkS")
			(hide yes)
			(effects
				(font
					(size 1.27 1.27)
				)
			)
		)
		(property "Value" ""
			(at 0 0 0)
			(layer "F.Fab")
			(effects
				(font
					(size 1.27 1.27)
				)
			)
		)
		(duplicate_pad_numbers_are_jumpers no)
		(fp_line
			(start -0.7874 -0.4064)
			(end 0.7874 -0.4064)
			(stroke
				(width 0.1524)
				(type default)
			)
			(layer "F.SilkS")
		)
		(fp_line
			(start -0.7874 0.4064)
			(end -0.7874 -0.4064)
			(stroke
				(width 0.1524)
				(type default)
			)
			(layer "F.SilkS")
		)
		(fp_line
			(start 0.7874 -0.4064)
			(end 0.7874 0.4064)
			(stroke
				(width 0.1524)
				(type default)
			)
			(layer "F.SilkS")
		)
		(fp_line
			(start 0.7874 0.4064)
			(end -0.7874 0.4064)
			(stroke
				(width 0.1524)
				(type default)
			)
			(layer "F.SilkS")
		)
		(fp_line
			(start -0.67945 -0.305054)
			(end -0.12065 -0.305054)
			(stroke
				(width 0.1)
				(type default)
			)
			(layer "F.Fab")
		)
		(fp_line
			(start -0.67945 0.3048)
			(end -0.67945 -0.305054)
			(stroke
				(width 0.1)
				(type default)
			)
			(layer "F.Fab")
		)
		(fp_line
			(start -0.12065 -0.305054)
			(end -0.12065 -0.2794)
			(stroke
				(width 0.1)
				(type default)
			)
			(layer "F.Fab")
		)
		(fp_line
			(start -0.12065 -0.2794)
			(end 0.12065 -0.2794)
			(stroke
				(width 0.1)
				(type default)
			)
			(layer "F.Fab")
		)
		(fp_line
			(start -0.12065 0.2794)
			(end -0.12065 0.3048)
			(stroke
				(width 0.1)
				(type default)
			)
			(layer "F.Fab")
		)
		(fp_line
			(start -0.12065 0.3048)
			(end -0.67945 0.3048)
			(stroke
				(width 0.1)
				(type default)
			)
			(layer "F.Fab")
		)
		(fp_line
			(start 0.120396 0.2794)
			(end -0.12065 0.2794)
			(stroke
				(width 0.1)
				(type default)
			)
			(layer "F.Fab")
		)
		(fp_line
			(start 0.120396 0.3048)
			(end 0.120396 0.2794)
			(stroke
				(width 0.1)
				(type default)
			)
			(layer "F.Fab")
		)
		(fp_line
			(start 0.12065 -0.3048)
			(end 0.67945 -0.3048)
			(stroke
				(width 0.1)
				(type default)
			)
			(layer "F.Fab")
		)
		(fp_line
			(start 0.12065 -0.2794)
			(end 0.12065 -0.3048)
			(stroke
				(width 0.1)
				(type default)
			)
			(layer "F.Fab")
		)
		(fp_line
			(start 0.67945 -0.3048)
			(end 0.67945 0.3048)
			(stroke
				(width 0.1)
				(type default)
			)
			(layer "F.Fab")
		)
		(fp_line
			(start 0.67945 0.3048)
			(end 0.120396 0.3048)
			(stroke
				(width 0.1)
				(type default)
			)
			(layer "F.Fab")
		)
		(pad "1" smd circle
			(at -0.40005 0)
			(size 0 0)
			(layers "F.Cu" "F.Mask" "F.Paste")
			(net "SMB_LM75_3_3V3AUX_SCL_R")
		)
		(pad "2" smd circle
			(at 0.40005 0)
			(size 0 0)
			(layers "F.Cu" "F.Mask" "F.Paste")
			(net "SMB_LM75_3_3V3AUX_SCL")
		)
	)
	(footprint ""
		(layer "F.Cu")
		(at 214.43188 -50.637948 90)
		(property "Reference" "R3754"
			(at 0 0 90)
			(layer "F.SilkS")
			(hide yes)
			(effects
				(font
					(size 1.27 1.27)
				)
			)
		)
		(property "Value" ""
			(at 0 0 90)
			(layer "F.Fab")
			(effects
				(font
					(size 1.27 1.27)
				)
			)
		)
		(duplicate_pad_numbers_are_jumpers no)
		(fp_line
			(start 0.7874 -0.4064)
			(end 0.7874 0.4064)
			(stroke
				(width 0.1524)
				(type default)
			)
			(layer "F.SilkS")
		)
		(fp_line
			(start -0.7874 -0.4064)
			(end 0.7874 -0.4064)
			(stroke
				(width 0.1524)
				(type default)
			)
			(layer "F.SilkS")
		)
		(fp_line
			(start 0.7874 0.4064)
			(end -0.7874 0.4064)
			(stroke
				(width 0.1524)
				(type default)
			)
			(layer "F.SilkS")
		)
		(fp_line
			(start -0.7874 0.4064)
			(end -0.7874 -0.4064)
			(stroke
				(width 0.1524)
				(type default)
			)
			(layer "F.SilkS")
		)
		(fp_line
			(start -0.12065 -0.305054)
			(end -0.12065 -0.2794)
			(stroke
				(width 0.1)
				(type default)
			)
			(layer "F.Fab")
		)
		(fp_line
			(start -0.67945 -0.305054)
			(end -0.12065 -0.305054)
			(stroke
				(width 0.1)
				(type default)
			)
			(layer "F.Fab")
		)
		(fp_line
			(start 0.67945 -0.3048)
			(end 0.67945 0.3048)
			(stroke
				(width 0.1)
				(type default)
			)
			(layer "F.Fab")
		)
		(fp_line
			(start 0.12065 -0.3048)
			(end 0.67945 -0.3048)
			(stroke
				(width 0.1)
				(type default)
			)
			(layer "F.Fab")
		)
		(fp_line
			(start 0.12065 -0.2794)
			(end 0.12065 -0.3048)
			(stroke
				(width 0.1)
				(type default)
			)
			(layer "F.Fab")
		)
		(fp_line
			(start -0.12065 -0.2794)
			(end 0.12065 -0.2794)
			(stroke
				(width 0.1)
				(type default)
			)
			(layer "F.Fab")
		)
		(fp_line
			(start 0.120396 0.2794)
			(end -0.12065 0.2794)
			(stroke
				(width 0.1)
				(type default)
			)
			(layer "F.Fab")
		)
		(fp_line
			(start -0.12065 0.2794)
			(end -0.12065 0.3048)
			(stroke
				(width 0.1)
				(type default)
			)
			(layer "F.Fab")
		)
		(fp_line
			(start 0.67945 0.3048)
			(end 0.120396 0.3048)
			(stroke
				(width 0.1)
				(type default)
			)
			(layer "F.Fab")
		)
		(fp_line
			(start 0.120396 0.3048)
			(end 0.120396 0.2794)
			(stroke
				(width 0.1)
				(type default)
			)
			(layer "F.Fab")
		)
		(fp_line
			(start -0.12065 0.3048)
			(end -0.67945 0.3048)
			(stroke
				(width 0.1)
				(type default)
			)
			(layer "F.Fab")
		)
		(fp_line
			(start -0.67945 0.3048)
			(end -0.67945 -0.305054)
			(stroke
				(width 0.1)
				(type default)
			)
			(layer "F.Fab")
		)
		(pad "1" smd circle
			(at -0.40005 0 90)
			(size 0 0)
			(layers "F.Cu" "F.Mask" "F.Paste")
			(net "SMB_INA230_2_3V3AUX_SCL_R")
		)
		(pad "2" smd circle
			(at 0.40005 0 90)
			(size 0 0)
			(layers "F.Cu" "F.Mask" "F.Paste")
			(net "SMB_INA230_2_3V3AUX_SCL_R1")
		)
	)
	(footprint ""
		(layer "F.Cu")
		(at 185.59272 -418.06876 90)
		(property "Reference" "R4797"
			(at 0 0 90)
			(layer "F.SilkS")
			(hide yes)
			(effects
				(font
					(size 1.27 1.27)
				)
			)
		)
		(property "Value" ""
			(at 0 0 90)
			(layer "F.Fab")
			(effects
				(font
					(size 1.27 1.27)
				)
			)
		)
		(duplicate_pad_numbers_are_jumpers no)
		(fp_line
			(start 0.7874 -0.4064)
			(end 0.7874 0.4064)
			(stroke
				(width 0.1524)
				(type default)
			)
			(layer "F.SilkS")
		)
		(fp_line
			(start -0.7874 -0.4064)
			(end 0.7874 -0.4064)
			(stroke
				(width 0.1524)
				(type default)
			)
			(layer "F.SilkS")
		)
		(fp_line
			(start 0.7874 0.4064)
			(end -0.7874 0.4064)
			(stroke
				(width 0.1524)
				(type default)
			)
			(layer "F.SilkS")
		)
		(fp_line
			(start -0.7874 0.4064)
			(end -0.7874 -0.4064)
			(stroke
				(width 0.1524)
				(type default)
			)
			(layer "F.SilkS")
		)
		(fp_line
			(start -0.12065 -0.305054)
			(end -0.12065 -0.2794)
			(stroke
				(width 0.1)
				(type default)
			)
			(layer "F.Fab")
		)
		(fp_line
			(start -0.67945 -0.305054)
			(end -0.12065 -0.305054)
			(stroke
				(width 0.1)
				(type default)
			)
			(layer "F.Fab")
		)
		(fp_line
			(start 0.67945 -0.3048)
			(end 0.67945 0.3048)
			(stroke
				(width 0.1)
				(type default)
			)
			(layer "F.Fab")
		)
		(fp_line
			(start 0.12065 -0.3048)
			(end 0.67945 -0.3048)
			(stroke
				(width 0.1)
				(type default)
			)
			(layer "F.Fab")
		)
		(fp_line
			(start 0.12065 -0.2794)
			(end 0.12065 -0.3048)
			(stroke
				(width 0.1)
				(type default)
			)
			(layer "F.Fab")
		)
		(fp_line
			(start -0.12065 -0.2794)
			(end 0.12065 -0.2794)
			(stroke
				(width 0.1)
				(type default)
			)
			(layer "F.Fab")
		)
		(fp_line
			(start 0.120396 0.2794)
			(end -0.12065 0.2794)
			(stroke
				(width 0.1)
				(type default)
			)
			(layer "F.Fab")
		)
		(fp_line
			(start -0.12065 0.2794)
			(end -0.12065 0.3048)
			(stroke
				(width 0.1)
				(type default)
			)
			(layer "F.Fab")
		)
		(fp_line
			(start 0.67945 0.3048)
			(end 0.120396 0.3048)
			(stroke
				(width 0.1)
				(type default)
			)
			(layer "F.Fab")
		)
		(fp_line
			(start 0.120396 0.3048)
			(end 0.120396 0.2794)
			(stroke
				(width 0.1)
				(type default)
			)
			(layer "F.Fab")
		)
		(fp_line
			(start -0.12065 0.3048)
			(end -0.67945 0.3048)
			(stroke
				(width 0.1)
				(type default)
			)
			(layer "F.Fab")
		)
		(fp_line
			(start -0.67945 0.3048)
			(end -0.67945 -0.305054)
			(stroke
				(width 0.1)
				(type default)
			)
			(layer "F.Fab")
		)
		(pad "1" smd circle
			(at -0.40005 0 90)
			(size 0 0)
			(layers "F.Cu" "F.Mask" "F.Paste")
			(net "P3V3_AUX")
		)
		(pad "2" smd circle
			(at 0.40005 0 90)
			(size 0 0)
			(layers "F.Cu" "F.Mask" "F.Paste")
			(net "A_HSC_LOW_GATE")
		)
	)
	(footprint ""
		(layer "F.Cu")
		(at 277.9014 -398.78 90)
		(property "Reference" "PPQ9"
			(at -8.190992 -2.0828 0)
			(unlocked yes)
			(layer "F.SilkS")
			(effects
				(font
					(size 0.7874 0.5842)
					(thickness 0.1524)
				)
				(justify left)
			)
		)
		(property "Value" ""
			(at 0 0 90)
			(layer "F.Fab")
			(effects
				(font
					(size 1.27 1.27)
				)
			)
		)
		(duplicate_pad_numbers_are_jumpers no)
		(fp_line
			(start 2.350008 -2.649982)
			(end 2.350008 -2.4892)
			(stroke
				(width 0.1524)
				(type default)
			)
			(layer "F.SilkS")
		)
		(fp_line
			(start -2.350008 -2.649982)
			(end 2.350008 -2.649982)
			(stroke
				(width 0.1524)
				(type default)
			)
			(layer "F.SilkS")
		)
		(fp_line
			(start -2.350008 -2.4384)
			(end -2.350008 -2.649982)
			(stroke
				(width 0.1524)
				(type default)
			)
			(layer "F.SilkS")
		)
		(fp_line
			(start 2.350008 2.4892)
			(end 2.350008 2.649982)
			(stroke
				(width 0.1524)
				(type default)
			)
			(layer "F.SilkS")
		)
		(fp_line
			(start 2.350008 2.649982)
			(end -2.350008 2.649982)
			(stroke
				(width 0.1524)
				(type default)
			)
			(layer "F.SilkS")
		)
		(fp_line
			(start -2.350008 2.649982)
			(end -2.350008 2.413)
			(stroke
				(width 0.1524)
				(type default)
			)
			(layer "F.SilkS")
		)
		(fp_poly
			(pts
				(xy -3.717544 -1.905) (xy -4.758944 -2.3241) (xy -4.758944 -1.524)
			)
			(stroke
				(width 0)
				(type default)
			)
			(fill yes)
			(layer "F.SilkS")
		)
		(fp_line
			(start 2.350008 -2.649982)
			(end 2.350008 2.649982)
			(stroke
				(width 0.1)
				(type default)
			)
			(layer "F.Fab")
		)
		(fp_line
			(start -2.350008 -2.649982)
			(end 2.350008 -2.649982)
			(stroke
				(width 0.1)
				(type default)
			)
			(layer "F.Fab")
		)
		(fp_line
			(start 2.350008 2.649982)
			(end -2.350008 2.649982)
			(stroke
				(width 0.1)
				(type default)
			)
			(layer "F.Fab")
		)
		(fp_line
			(start -2.350008 2.649982)
			(end -2.350008 -2.649982)
			(stroke
				(width 0.1)
				(type default)
			)
			(layer "F.Fab")
		)
		(fp_poly
			(pts
				(xy -3.717544 -1.905) (xy -4.758944 -2.3241) (xy -4.758944 -1.524)
			)
			(stroke
				(width 0)
				(type default)
			)
			(fill yes)
			(layer "F.Fab")
		)
		(pad "1" smd rect
			(at -2.999994 -1.905)
			(size 0.7112 1.1684)
			(layers "F.Cu" "F.Mask" "F.Paste")
			(net "P12V_AUX")
		)
		(pad "2" smd rect
			(at -2.999994 -0.635)
			(size 0.7112 1.1684)
			(layers "F.Cu" "F.Mask" "F.Paste")
			(net "P12V_AUX")
		)
		(pad "3" smd rect
			(at -2.999994 0.635)
			(size 0.7112 1.1684)
			(layers "F.Cu" "F.Mask" "F.Paste")
			(net "P12V_AUX")
		)
		(pad "4" smd rect
			(at -2.999994 1.905)
			(size 0.7112 1.1684)
			(layers "F.Cu" "F.Mask" "F.Paste")
			(net "MB0_CM_GATE_G0")
		)
		(pad "5" smd circle
			(at 0.925068 0)
			(size 0 0)
			(layers "F.Cu" "F.Mask" "F.Paste")
			(net "P12V_MAIN_R_0")
		)
		(zone
			(layer "F.Cu")
			(hatch none 0.5)
			(connect_pads
				(clearance 0)
			)
			(min_thickness 0.25)
			(keepout
				(tracks not_allowed)
				(vias allowed)
				(pads allowed)
				(copperpour not_allowed)
				(footprints allowed)
			)
			(placement
				(enabled no)
				(sheetname "")
			)
			(fill
				(thermal_gap 0.5)
				(thermal_bridge_width 0.5)
				(island_removal_mode 0)
			)
			(polygon
				(pts
					(xy 275.7424 -397.3322) (xy 280.0604 -397.3322) (xy 280.543 -397.3322) (xy 280.543 -396.4305) (xy 275.2598 -396.4305)
					(xy 275.2598 -397.3322)
				)
			)
		)
	)
	(footprint ""
		(layer "F.Cu")
		(at 223.868488 -232.77957 90)
		(property "Reference" "C570"
			(at 0 0 90)
			(layer "F.SilkS")
			(hide yes)
			(effects
				(font
					(size 1.27 1.27)
				)
			)
		)
		(property "Value" ""
			(at 0 0 90)
			(layer "F.Fab")
			(effects
				(font
					(size 1.27 1.27)
				)
			)
		)
		(duplicate_pad_numbers_are_jumpers no)
		(fp_line
			(start 0.7874 -0.4064)
			(end 0.7874 0.4064)
			(stroke
				(width 0.1524)
				(type default)
			)
			(layer "F.SilkS")
		)
		(fp_line
			(start -0.7874 -0.4064)
			(end 0.7874 -0.4064)
			(stroke
				(width 0.1524)
				(type default)
			)
			(layer "F.SilkS")
		)
		(fp_line
			(start 0.7874 0.4064)
			(end -0.7874 0.4064)
			(stroke
				(width 0.1524)
				(type default)
			)
			(layer "F.SilkS")
		)
		(fp_line
			(start -0.7874 0.4064)
			(end -0.7874 -0.4064)
			(stroke
				(width 0.1524)
				(type default)
			)
			(layer "F.SilkS")
		)
		(fp_line
			(start -0.12065 -0.305054)
			(end -0.12065 -0.2794)
			(stroke
				(width 0.1)
				(type default)
			)
			(layer "F.Fab")
		)
		(fp_line
			(start -0.67945 -0.305054)
			(end -0.12065 -0.305054)
			(stroke
				(width 0.1)
				(type default)
			)
			(layer "F.Fab")
		)
		(fp_line
			(start 0.67945 -0.3048)
			(end 0.67945 0.3048)
			(stroke
				(width 0.1)
				(type default)
			)
			(layer "F.Fab")
		)
		(fp_line
			(start 0.12065 -0.3048)
			(end 0.67945 -0.3048)
			(stroke
				(width 0.1)
				(type default)
			)
			(layer "F.Fab")
		)
		(fp_line
			(start 0.12065 -0.2794)
			(end 0.12065 -0.3048)
			(stroke
				(width 0.1)
				(type default)
			)
			(layer "F.Fab")
		)
		(fp_line
			(start -0.12065 -0.2794)
			(end 0.12065 -0.2794)
			(stroke
				(width 0.1)
				(type default)
			)
			(layer "F.Fab")
		)
		(fp_line
			(start 0.120396 0.2794)
			(end -0.12065 0.2794)
			(stroke
				(width 0.1)
				(type default)
			)
			(layer "F.Fab")
		)
		(fp_line
			(start -0.12065 0.2794)
			(end -0.12065 0.3048)
			(stroke
				(width 0.1)
				(type default)
			)
			(layer "F.Fab")
		)
		(fp_line
			(start 0.67945 0.3048)
			(end 0.120396 0.3048)
			(stroke
				(width 0.1)
				(type default)
			)
			(layer "F.Fab")
		)
		(fp_line
			(start 0.120396 0.3048)
			(end 0.120396 0.2794)
			(stroke
				(width 0.1)
				(type default)
			)
			(layer "F.Fab")
		)
		(fp_line
			(start -0.12065 0.3048)
			(end -0.67945 0.3048)
			(stroke
				(width 0.1)
				(type default)
			)
			(layer "F.Fab")
		)
		(fp_line
			(start -0.67945 0.3048)
			(end -0.67945 -0.305054)
			(stroke
				(width 0.1)
				(type default)
			)
			(layer "F.Fab")
		)
		(pad "1" smd circle
			(at -0.40005 0 90)
			(size 0 0)
			(layers "F.Cu" "F.Mask" "F.Paste")
			(net "P3V3_AUX")
		)
		(pad "2" smd circle
			(at 0.40005 0 90)
			(size 0 0)
			(layers "F.Cu" "F.Mask" "F.Paste")
			(net "GND")
		)
	)
)
